(kicad_pcb
	(version 20260206)
	(generator "pcbnew")
	(generator_version "10.0")
	(general
		(thickness 1.6)
		(legacy_teardrops no)
	)
	(paper "A4")
	(title_block
		(title "Bryce Canyon_F.DPB_16315-1-OCP.brd")
		(comment 1 "Bryce Canyon / footprints 1039-1045 of 2223")
	)
	(layers
		(0 "F.Cu" signal "TOP")
		(4 "In1.Cu" signal "L2GND")
		(6 "In2.Cu" signal "L3")
		(8 "In3.Cu" signal "L4GND")
		(10 "In4.Cu" signal "L5")
		(12 "In5.Cu" signal "L6VCC")
		(14 "In6.Cu" signal "L7VCC")
		(16 "In7.Cu" signal "L8")
		(18 "In8.Cu" signal "L9GND")
		(20 "In9.Cu" signal "L10")
		(22 "In10.Cu" signal "L11GND")
		(2 "B.Cu" signal "BOTTOM")
		(9 "F.Adhes" user "F.Adhesive")
		(11 "B.Adhes" user "B.Adhesive")
		(13 "F.Paste" user "Package Geometry/Pastemask Top")
		(15 "B.Paste" user "Package Geometry/Pastemask Bottom")
		(5 "F.SilkS" user "Ref Des/Silkscreen Top")
		(7 "B.SilkS" user "Ref Des/Silkscreen Bottom")
		(1 "F.Mask" user "Board Geometry/Soldermask Top")
		(3 "B.Mask" user "Board Geometry/Soldermask Bottom")
		(17 "Dwgs.User" user "User.Drawings")
		(19 "Cmts.User" user "User.Comments")
		(21 "Eco1.User" user "User.Eco1")
		(23 "Eco2.User" user "User.Eco2")
		(25 "Edge.Cuts" user "Board Geometry/Outline")
		(27 "Margin" user)
		(31 "F.CrtYd" user "Package Geometry/Place Bound Top")
		(29 "B.CrtYd" user "Package Geometry/Place Bound Bottom")
		(35 "F.Fab" user "Ref Des/Assembly Top")
		(33 "B.Fab" user "Ref Des/Assembly Bottom")
	)
	(footprint ""
		(layer "F.Cu")
		(at 115.4684 -289.6108)
		(property "Reference" "Q20"
			(at 0 0 0)
			(layer "F.SilkS")
			(hide yes)
			(effects
				(font
					(size 1.27 1.27)
				)
			)
		)
		(property "Value" "AO4407AL-GP"
			(at -3.707384 -1.5367 0)
			(unlocked yes)
			(layer "F.Fab")
			(hide yes)
			(effects
				(font
					(size 1.016 1.016)
					(thickness 0.1524)
				)
			)
		)
		(property "Device Type" "SOIC8H69"
			(at -3.707384 -3.0607 0)
			(unlocked yes)
			(layer "F.Fab")
			(hide yes)
			(effects
				(font
					(size 1.016 1.016)
					(thickness 0.1524)
				)
			)
		)
		(duplicate_pad_numbers_are_jumpers no)
		(fp_line
			(start -2.7432 -1.4224)
			(end -2.7432 1.4224)
			(stroke
				(width 0.1524)
				(type default)
			)
			(layer "F.SilkS")
		)
		(fp_line
			(start -2.7432 1.4224)
			(end -2.6416 1.4224)
			(stroke
				(width 0.1524)
				(type default)
			)
			(layer "F.SilkS")
		)
		(fp_line
			(start -2.7432 1.4224)
			(end 2.1336 1.4224)
			(stroke
				(width 0.1524)
				(type default)
			)
			(layer "F.SilkS")
		)
		(fp_line
			(start -2.7178 -0.508)
			(end -2.1844 -0.0508)
			(stroke
				(width 0.1524)
				(type default)
			)
			(layer "F.SilkS")
		)
		(fp_line
			(start -2.6289 3.4417)
			(end -2.6289 1.4732)
			(stroke
				(width 0.381)
				(type default)
			)
			(layer "F.SilkS")
		)
		(fp_line
			(start -2.1844 -0.0508)
			(end -2.7178 0.508)
			(stroke
				(width 0.1524)
				(type default)
			)
			(layer "F.SilkS")
		)
		(fp_line
			(start 2.1336 -1.4224)
			(end -2.7432 -1.4224)
			(stroke
				(width 0.1524)
				(type default)
			)
			(layer "F.SilkS")
		)
		(fp_line
			(start 2.1336 1.4224)
			(end 2.1336 -1.4224)
			(stroke
				(width 0.1524)
				(type default)
			)
			(layer "F.SilkS")
		)
		(fp_poly
			(pts
				(xy -2.2098 -1.4224) (xy -2.2098 1.4224) (xy 2.2098 1.4224) (xy 2.2098 -1.4224)
			)
			(stroke
				(width 0)
				(type default)
			)
			(fill yes)
			(layer "F.SilkS")
		)
		(fp_rect
			(start -2.450084 2.999994)
			(end 2.450084 -2.999994)
			(stroke
				(width 0)
				(type default)
			)
			(fill no)
			(layer "F.CrtYd")
		)
		(fp_poly
			(pts
				(xy -2.8194 3.6322) (xy -2.8194 -3.6322) (xy 2.8194 -3.6322) (xy 2.8194 1.18364) (xy 2.450084 1.18364)
				(xy 2.450084 -2.999994) (xy -2.450084 -2.999994) (xy -2.450084 2.999994) (xy 2.450084 2.999994)
				(xy 2.450084 1.18618) (xy 2.8194 1.18618) (xy 2.8194 3.6322)
			)
			(stroke
				(width 0)
				(type default)
			)
			(fill no)
			(layer "F.CrtYd")
		)
		(fp_rect
			(start -2.8194 3.6322)
			(end 2.8194 -3.6322)
			(stroke
				(width 0)
				(type default)
			)
			(fill no)
			(layer "F.Fab")
		)
		(pad "1" smd rect
			(at -1.905 2.54)
			(size 0.635 1.651)
			(layers "F.Cu" "F.Mask" "F.Paste")
			(net "P12V_A")
		)
		(pad "2" smd rect
			(at -0.635 2.54)
			(size 0.635 1.651)
			(layers "F.Cu" "F.Mask" "F.Paste")
			(net "P12V_A")
		)
		(pad "3" smd rect
			(at 0.635 2.54)
			(size 0.635 1.651)
			(layers "F.Cu" "F.Mask" "F.Paste")
			(net "P12V_A")
		)
		(pad "4" smd rect
			(at 1.905 2.54)
			(size 0.635 1.651)
			(layers "F.Cu" "F.Mask" "F.Paste")
			(net "SW_HDD_N3")
		)
		(pad "5" smd rect
			(at 1.905 -2.54)
			(size 0.635 1.651)
			(layers "F.Cu" "F.Mask" "F.Paste")
			(net "P12V_HDD3")
		)
		(pad "6" smd rect
			(at 0.635 -2.54)
			(size 0.635 1.651)
			(layers "F.Cu" "F.Mask" "F.Paste")
			(net "P12V_HDD3")
		)
		(pad "7" smd rect
			(at -0.635 -2.54)
			(size 0.635 1.651)
			(layers "F.Cu" "F.Mask" "F.Paste")
			(net "P12V_HDD3")
		)
		(pad "8" smd rect
			(at -1.905 -2.54)
			(size 0.635 1.651)
			(layers "F.Cu" "F.Mask" "F.Paste")
			(net "P12V_HDD3")
		)
	)
	(footprint ""
		(layer "F.Cu")
		(at 469.942926 -169.523918 90)
		(property "Reference" "C348"
			(at 0 0 90)
			(layer "F.SilkS")
			(hide yes)
			(effects
				(font
					(size 1.27 1.27)
				)
			)
		)
		(property "Value" "SCD033U25V2KX-GP"
			(at 1.1811 -2.7051 90)
			(unlocked yes)
			(layer "F.Fab")
			(hide yes)
			(effects
				(font
					(size 1.016 1.016)
					(thickness 0.1524)
				)
			)
		)
		(property "Device Type" "C402H22"
			(at 1.1811 -4.2291 90)
			(unlocked yes)
			(layer "F.Fab")
			(hide yes)
			(effects
				(font
					(size 1.016 1.016)
					(thickness 0.1524)
				)
			)
		)
		(duplicate_pad_numbers_are_jumpers no)
		(fp_rect
			(start -0.4318 0.9525)
			(end 0.4318 -0.9525)
			(stroke
				(width 0)
				(type default)
			)
			(fill no)
			(layer "F.CrtYd")
		)
		(fp_rect
			(start -0.4318 0.9525)
			(end 0.4318 -0.9525)
			(stroke
				(width 0)
				(type default)
			)
			(fill no)
			(layer "F.Fab")
		)
		(pad "1" smd custom
			(at 0 -0.4445 90)
			(size 0.1524 0.1524)
			(layers "F.Cu" "F.Mask" "F.Paste")
			(net "P12V_A")
			(options
				(clearance outline)
				(anchor circle)
			)
			(primitives
				(gr_poly
					(pts
						(arc
							(start 0.3048 -0.2032)
							(mid 0.275042 -0.275042)
							(end 0.2032 -0.3048)
						)
						(arc
							(start -0.2032 -0.3048)
							(mid -0.275042 -0.275042)
							(end -0.3048 -0.2032)
						)
						(arc
							(start -0.3048 0.2032)
							(mid -0.275042 0.275042)
							(end -0.2032 0.3048)
						)
						(arc
							(start 0.2032 0.3048)
							(mid 0.275042 0.275042)
							(end 0.3048 0.2032)
						)
					)
					(width 0)
					(fill yes)
				)
			)
		)
		(pad "2" smd custom
			(at 0 0.4445 90)
			(size 0.1524 0.1524)
			(layers "F.Cu" "F.Mask" "F.Paste")
			(net "SW_HDD_N23")
			(options
				(clearance outline)
				(anchor circle)
			)
			(primitives
				(gr_poly
					(pts
						(arc
							(start 0.3048 -0.2032)
							(mid 0.275042 -0.275042)
							(end 0.2032 -0.3048)
						)
						(arc
							(start -0.2032 -0.3048)
							(mid -0.275042 -0.275042)
							(end -0.3048 -0.2032)
						)
						(arc
							(start -0.3048 0.2032)
							(mid -0.275042 0.275042)
							(end -0.2032 0.3048)
						)
						(arc
							(start 0.2032 0.3048)
							(mid 0.275042 0.275042)
							(end 0.3048 0.2032)
						)
					)
					(width 0)
					(fill yes)
				)
			)
		)
	)
	(footprint ""
		(layer "F.Cu")
		(at 395.45895 -180.826918 180)
		(property "Reference" "C301"
			(at 0 0 180)
			(layer "F.SilkS")
			(hide yes)
			(effects
				(font
					(size 1.27 1.27)
				)
			)
		)
		(property "Value" "SC10U16V6KX-2GP"
			(at -0.0762 -5.1308 180)
			(unlocked yes)
			(layer "F.Fab")
			(hide yes)
			(effects
				(font
					(size 1.016 1.016)
					(thickness 0.1524)
				)
			)
		)
		(property "Device Type" "C1206H71"
			(at -0.127 -6.6548 180)
			(unlocked yes)
			(layer "F.Fab")
			(hide yes)
			(effects
				(font
					(size 1.016 1.016)
					(thickness 0.1524)
				)
			)
		)
		(duplicate_pad_numbers_are_jumpers no)
		(fp_line
			(start 1.016 2.2352)
			(end -1.016 2.2352)
			(stroke
				(width 0.1524)
				(type default)
			)
			(layer "F.SilkS")
		)
		(fp_line
			(start 1.016 0.8382)
			(end 1.016 2.2352)
			(stroke
				(width 0.1524)
				(type default)
			)
			(layer "F.SilkS")
		)
		(fp_line
			(start 1.016 -2.2352)
			(end 1.016 -0.8382)
			(stroke
				(width 0.1524)
				(type default)
			)
			(layer "F.SilkS")
		)
		(fp_line
			(start -1.016 2.2352)
			(end -1.016 0.8382)
			(stroke
				(width 0.1524)
				(type default)
			)
			(layer "F.SilkS")
		)
		(fp_line
			(start -1.016 -0.8382)
			(end -1.016 -2.2352)
			(stroke
				(width 0.1524)
				(type default)
			)
			(layer "F.SilkS")
		)
		(fp_line
			(start -1.016 -2.2352)
			(end 1.016 -2.2352)
			(stroke
				(width 0.1524)
				(type default)
			)
			(layer "F.SilkS")
		)
		(fp_rect
			(start -1.0922 2.3114)
			(end 1.0922 -2.3114)
			(stroke
				(width 0)
				(type default)
			)
			(fill no)
			(layer "F.CrtYd")
		)
		(fp_poly
			(pts
				(xy 1.0922 -2.3114) (xy 1.0922 2.3114) (xy -1.0922 2.3114) (xy -1.0922 -2.3114)
			)
			(stroke
				(width 0)
				(type default)
			)
			(fill no)
			(layer "F.Fab")
		)
		(pad "1" smd rect
			(at 0 -1.397 180)
			(size 1.651 1.27)
			(layers "F.Cu" "F.Mask" "F.Paste")
			(net "P5V_HDD20")
		)
		(pad "2" smd rect
			(at 0 1.397 180)
			(size 1.651 1.27)
			(layers "F.Cu" "F.Mask" "F.Paste")
			(net "GND")
		)
	)
	(footprint ""
		(layer "F.Cu")
		(at 162.378898 -180.064918 90)
		(property "Reference" "R502"
			(at 0 0 90)
			(layer "F.SilkS")
			(hide yes)
			(effects
				(font
					(size 1.27 1.27)
				)
			)
		)
		(property "Value" "220R3F-1-GP"
			(at -0.0254 -2.5146 90)
			(unlocked yes)
			(layer "F.Fab")
			(hide yes)
			(effects
				(font
					(size 1.016 1.016)
					(thickness 0.1524)
				)
			)
		)
		(property "Device Type" "R603H22"
			(at -0.0254 -4.0386 90)
			(unlocked yes)
			(layer "F.Fab")
			(hide yes)
			(effects
				(font
					(size 1.016 1.016)
					(thickness 0.1524)
				)
			)
		)
		(duplicate_pad_numbers_are_jumpers no)
		(fp_line
			(start 0.2032 0)
			(end 0.4826 0)
			(stroke
				(width 0.2032)
				(type default)
			)
			(layer "F.SilkS")
		)
		(fp_line
			(start -0.4826 0)
			(end -0.2032 0)
			(stroke
				(width 0.2032)
				(type default)
			)
			(layer "F.SilkS")
		)
		(fp_rect
			(start -0.5842 1.3335)
			(end 0.5842 -1.3335)
			(stroke
				(width 0)
				(type default)
			)
			(fill no)
			(layer "F.CrtYd")
		)
		(fp_rect
			(start -0.5842 1.3335)
			(end 0.5842 -1.3335)
			(stroke
				(width 0)
				(type default)
			)
			(fill no)
			(layer "F.Fab")
		)
		(pad "1" smd custom
			(at 0 -0.762 90)
			(size 0.2159 0.2159)
			(layers "F.Cu" "F.Mask" "F.Paste")
			(net "HDD_PRSNT_16")
			(options
				(clearance outline)
				(anchor circle)
			)
			(primitives
				(gr_poly
					(pts
						(arc
							(start -0.3302 -0.4318)
							(mid -0.402042 -0.402042)
							(end -0.4318 -0.3302)
						)
						(arc
							(start -0.4318 0.3302)
							(mid -0.402042 0.402042)
							(end -0.3302 0.4318)
						)
						(arc
							(start 0.3302 0.4318)
							(mid 0.402042 0.402042)
							(end 0.4318 0.3302)
						)
						(arc
							(start 0.4318 -0.3302)
							(mid 0.402042 -0.402042)
							(end 0.3302 -0.4318)
						)
					)
					(width 0)
					(fill yes)
				)
			)
		)
		(pad "2" smd custom
			(at 0 0.762 90)
			(size 0.2159 0.2159)
			(layers "F.Cu" "F.Mask" "F.Paste")
			(net "DRIVE_A_16_INS")
			(options
				(clearance outline)
				(anchor circle)
			)
			(primitives
				(gr_poly
					(pts
						(arc
							(start -0.3302 -0.4318)
							(mid -0.402042 -0.402042)
							(end -0.4318 -0.3302)
						)
						(arc
							(start -0.4318 0.3302)
							(mid -0.402042 0.402042)
							(end -0.3302 0.4318)
						)
						(arc
							(start 0.3302 0.4318)
							(mid 0.402042 0.402042)
							(end 0.4318 0.3302)
						)
						(arc
							(start 0.4318 -0.3302)
							(mid 0.402042 -0.402042)
							(end 0.3302 -0.4318)
						)
					)
					(width 0)
					(fill yes)
				)
			)
		)
	)
	(footprint ""
		(layer "F.Cu")
		(at 144.215866 -145.372074 180)
		(property "Reference" "C550"
			(at 0 0 180)
			(layer "F.SilkS")
			(hide yes)
			(effects
				(font
					(size 1.27 1.27)
				)
			)
		)
		(property "Value" "SCD1U25V2KX-2-GP"
			(at 1.1811 -2.7051 180)
			(unlocked yes)
			(layer "F.Fab")
			(hide yes)
			(effects
				(font
					(size 1.016 1.016)
					(thickness 0.1524)
				)
			)
		)
		(property "Device Type" "C402H22"
			(at 1.1811 -4.2291 180)
			(unlocked yes)
			(layer "F.Fab")
			(hide yes)
			(effects
				(font
					(size 1.016 1.016)
					(thickness 0.1524)
				)
			)
		)
		(duplicate_pad_numbers_are_jumpers no)
		(fp_rect
			(start -0.4318 0.9525)
			(end 0.4318 -0.9525)
			(stroke
				(width 0)
				(type default)
			)
			(fill no)
			(layer "F.CrtYd")
		)
		(fp_rect
			(start -0.4318 0.9525)
			(end 0.4318 -0.9525)
			(stroke
				(width 0)
				(type default)
			)
			(fill no)
			(layer "F.Fab")
		)
		(pad "1" smd custom
			(at 0 -0.4445 180)
			(size 0.1524 0.1524)
			(layers "F.Cu" "F.Mask" "F.Paste")
			(net "MB0_ISTART_R")
			(options
				(clearance outline)
				(anchor circle)
			)
			(primitives
				(gr_poly
					(pts
						(arc
							(start 0.3048 -0.2032)
							(mid 0.275042 -0.275042)
							(end 0.2032 -0.3048)
						)
						(arc
							(start -0.2032 -0.3048)
							(mid -0.275042 -0.275042)
							(end -0.3048 -0.2032)
						)
						(arc
							(start -0.3048 0.2032)
							(mid -0.275042 0.275042)
							(end -0.2032 0.3048)
						)
						(arc
							(start 0.2032 0.3048)
							(mid 0.275042 0.275042)
							(end 0.3048 0.2032)
						)
					)
					(width 0)
					(fill yes)
				)
			)
		)
		(pad "2" smd custom
			(at 0 0.4445 180)
			(size 0.1524 0.1524)
			(layers "F.Cu" "F.Mask" "F.Paste")
			(net "AGND_CURRENT_MONOA")
			(options
				(clearance outline)
				(anchor circle)
			)
			(primitives
				(gr_poly
					(pts
						(arc
							(start 0.3048 -0.2032)
							(mid 0.275042 -0.275042)
							(end 0.2032 -0.3048)
						)
						(arc
							(start -0.2032 -0.3048)
							(mid -0.275042 -0.275042)
							(end -0.3048 -0.2032)
						)
						(arc
							(start -0.3048 0.2032)
							(mid -0.275042 0.275042)
							(end -0.2032 0.3048)
						)
						(arc
							(start 0.2032 0.3048)
							(mid 0.275042 0.275042)
							(end 0.3048 0.2032)
						)
					)
					(width 0)
					(fill yes)
				)
			)
		)
	)
	(footprint ""
		(layer "F.Cu")
		(at 393.674854 -92.799916)
		(property "Reference" ""
			(at 0 0 0)
			(layer "F.SilkS")
			(hide yes)
			(effects
				(font
					(size 1.27 1.27)
				)
			)
		)
		(property "Value" "*"
			(at -8.398764 -8.057642 0)
			(unlocked yes)
			(layer "F.Fab")
			(hide yes)
			(effects
				(font
					(size 1.016 1.016)
					(thickness 0.1524)
				)
			)
		)
		(duplicate_pad_numbers_are_jumpers no)
		(fp_poly
			(pts
				(arc
					(start 7.3152 0)
					(mid 0 7.3152)
					(end -7.3152 0)
				)
				(arc
					(start -7.3152 -5.9944)
					(mid 0 -13.3096)
					(end 7.3152 -5.9944)
				)
			)
			(stroke
				(width 0)
				(type default)
			)
			(fill no)
			(layer "B.CrtYd")
		)
		(fp_poly
			(pts
				(arc
					(start 7.3152 0)
					(mid 0 7.3152)
					(end -7.3152 0)
				)
				(arc
					(start -7.3152 -5.9944)
					(mid 0 -13.3096)
					(end 7.3152 -5.9944)
				)
			)
			(stroke
				(width 0)
				(type default)
			)
			(fill no)
			(layer "F.CrtYd")
		)
		(fp_poly
			(pts
				(arc
					(start 7.3152 0)
					(mid 0 7.3152)
					(end -7.3152 0)
				)
				(arc
					(start -7.3152 -5.9944)
					(mid 0 -13.3096)
					(end 7.3152 -5.9944)
				)
			)
			(stroke
				(width 0)
				(type default)
			)
			(fill no)
			(layer "B.Fab")
		)
		(fp_poly
			(pts
				(arc
					(start 7.3152 0)
					(mid 0 7.3152)
					(end -7.3152 0)
				)
				(arc
					(start -7.3152 -5.9944)
					(mid 0 -13.3096)
					(end 7.3152 -5.9944)
				)
			)
			(stroke
				(width 0)
				(type default)
			)
			(fill no)
			(layer "F.Fab")
		)
		(pad "1" thru_hole oval
			(at 0 0)
			(size 14.0208 20.0152)
			(drill 0.0254
				(offset 0 -2.9972)
			)
			(layers "*.Cu" "*.Mask")
			(remove_unused_layers no)
			(net "Net_101")
			(clearance -1.002284)
			(thermal_gap 0.1524)
			(padstack
				(mode front_inner_back)
				(layer "Inner"
					(shape custom)
					(size 2.928012 2.928012)
					(options
						(anchor circle)
					)
					(primitives
						(gr_poly
							(pts
								(arc
									(start 4.571746 -2.084324)
									(mid 0.000333 7.430372)
									(end -4.571492 -2.084324)
								)
								(arc
									(start -4.571492 -2.084324)
									(mid -3.570296 -3.611977)
									(end -2.875026 -5.30098)
								)
								(arc
									(start -2.875026 -5.30098)
									(mid 0.000217 -7.43089)
									(end 2.87528 -5.30098)
								)
								(arc
									(start 2.87528 -5.30098)
									(mid 3.570511 -3.611956)
									(end 4.571746 -2.084324)
								)
							)
							(width 0)
							(fill yes)
						)
					)
					(clearance 0.1524)
				)
				(layer "B.Cu"
					(shape oval)
					(size 14.0208 20.0152)
					(offset 0 -2.9972)
					(clearance -1.002284)
				)
			)
		)
		(zone
			(layers "F.Cu" "B.Cu" "In1.Cu" "In2.Cu" "In3.Cu" "In4.Cu" "In5.Cu" "In6.Cu"
				"In7.Cu" "In8.Cu" "In9.Cu" "In10.Cu"
			)
			(hatch none 0.5)
			(connect_pads
				(clearance 0)
			)
			(min_thickness 0.25)
			(keepout
				(tracks not_allowed)
				(vias allowed)
				(pads allowed)
				(copperpour not_allowed)
				(footprints allowed)
			)
			(placement
				(enabled no)
				(sheetname "")
			)
			(fill
				(thermal_gap 0.5)
				(thermal_bridge_width 0.5)
				(island_removal_mode 0)
			)
			(polygon
				(pts
					(arc
						(start 386.664454 -98.794316)
						(mid 393.674854 -105.804716)
						(end 400.685254 -98.794316)
					)
					(arc
						(start 400.685254 -92.799916)
						(mid 393.674854 -85.789516)
						(end 386.664454 -92.799916)
					)
				)
			)
		)
	)
	(footprint ""
		(layer "F.Cu")
		(at 365.5568 -132.1054)
		(property "Reference" "C561"
			(at 0 0 0)
			(layer "F.SilkS")
			(hide yes)
			(effects
				(font
					(size 1.27 1.27)
				)
			)
		)
		(property "Value" "SCD1U25V2KX-2-GP"
			(at 1.1811 -2.7051 0)
			(unlocked yes)
			(layer "F.Fab")
			(hide yes)
			(effects
				(font
					(size 1.016 1.016)
					(thickness 0.1524)
				)
			)
		)
		(property "Device Type" "C402H22"
			(at 1.1811 -4.2291 0)
			(unlocked yes)
			(layer "F.Fab")
			(hide yes)
			(effects
				(font
					(size 1.016 1.016)
					(thickness 0.1524)
				)
			)
		)
		(duplicate_pad_numbers_are_jumpers no)
		(fp_rect
			(start -0.4318 0.9525)
			(end 0.4318 -0.9525)
			(stroke
				(width 0)
				(type default)
			)
			(fill no)
			(layer "F.CrtYd")
		)
		(fp_rect
			(start -0.4318 0.9525)
			(end 0.4318 -0.9525)
			(stroke
				(width 0)
				(type default)
			)
			(fill no)
			(layer "F.Fab")
		)
		(pad "1" smd custom
			(at 0 -0.4445)
			(size 0.1524 0.1524)
			(layers "F.Cu" "F.Mask" "F.Paste")
			(net "MB1_PSET_R")
			(options
				(clearance outline)
				(anchor circle)
			)
			(primitives
				(gr_poly
					(pts
						(arc
							(start 0.3048 -0.2032)
							(mid 0.275042 -0.275042)
							(end 0.2032 -0.3048)
						)
						(arc
							(start -0.2032 -0.3048)
							(mid -0.275042 -0.275042)
							(end -0.3048 -0.2032)
						)
						(arc
							(start -0.3048 0.2032)
							(mid -0.275042 0.275042)
							(end -0.2032 0.3048)
						)
						(arc
							(start 0.2032 0.3048)
							(mid 0.275042 0.275042)
							(end 0.3048 0.2032)
						)
					)
					(width 0)
					(fill yes)
				)
			)
		)
		(pad "2" smd custom
			(at 0 0.4445)
			(size 0.1524 0.1524)
			(layers "F.Cu" "F.Mask" "F.Paste")
			(net "AGND_CURRENT_MONOB")
			(options
				(clearance outline)
				(anchor circle)
			)
			(primitives
				(gr_poly
					(pts
						(arc
							(start 0.3048 -0.2032)
							(mid 0.275042 -0.275042)
							(end 0.2032 -0.3048)
						)
						(arc
							(start -0.2032 -0.3048)
							(mid -0.275042 -0.275042)
							(end -0.3048 -0.2032)
						)
						(arc
							(start -0.3048 0.2032)
							(mid -0.275042 0.275042)
							(end -0.2032 0.3048)
						)
						(arc
							(start 0.2032 0.3048)
							(mid 0.275042 0.275042)
							(end 0.3048 0.2032)
						)
					)
					(width 0)
					(fill yes)
				)
			)
		)
	)
)
